# BASEBOARD_FAB2 (Tioga Pass) — schematic netlist excerpt (pin names and nets, part order shuffled) for the footprints in the layout excerpt that follows; sources: Cadence DE-HDL packaged netlist, KiCad conversion of Wiwynn_Tioga_Pass_MB.brd

R25W140  RES  0.0 5% EMPTY  pkg 0402  page 144 : A = CLK_48M_USB_BMC ; B = CLK_48M_USB_BMC_R
C5D31  CAP_A  22.0UF 4V 20% X6S  pkg 0603V  page 42 : A = PVCCIN_CPU0 ; B = GND
R12W29  RES  0.0 5% EMPTY  pkg 0402  page 218 : A = TP_PVDDQ_DEF_MP1 ; B = PWRGD_PVDDQ_DEF

(kicad_pcb
	(version 20260206)
	(generator "pcbnew")
	(generator_version "10.0")
	(general
		(thickness 1.6)
		(legacy_teardrops no)
	)
	(paper "A4")
	(title_block
		(title "Wiwynn_Tioga_Pass_MB.brd")
		(comment 1 "Tioga Pass / footprints 451-453 of 4770")
	)
	(layers
		(0 "F.Cu" signal "TOP")
		(4 "In1.Cu" signal "L2GND")
		(6 "In2.Cu" signal "L3")
		(8 "In3.Cu" signal "L4GND")
		(10 "In4.Cu" signal "L5")
		(12 "In5.Cu" signal "L6GND")
		(14 "In6.Cu" signal "L7VCC")
		(16 "In7.Cu" signal "L8VCC")
		(18 "In8.Cu" signal "L9GND")
		(20 "In9.Cu" signal "L10")
		(22 "In10.Cu" signal "L11GND")
		(24 "In11.Cu" signal "L12")
		(26 "In12.Cu" signal "L13GND")
		(2 "B.Cu" signal "BOTTOM")
		(9 "F.Adhes" user "F.Adhesive")
		(11 "B.Adhes" user "B.Adhesive")
		(13 "F.Paste" user "Package Geometry/Pastemask Top")
		(15 "B.Paste" user "Package Geometry/Pastemask Bottom")
		(5 "F.SilkS" user "Ref Des/Silkscreen Top")
		(7 "B.SilkS" user "Ref Des/Silkscreen Bottom")
		(1 "F.Mask" user "Board Geometry/Soldermask Top")
		(3 "B.Mask" user "Board Geometry/Soldermask Bottom")
		(17 "Dwgs.User" user "User.Drawings")
		(19 "Cmts.User" user "User.Comments")
		(21 "Eco1.User" user "User.Eco1")
		(23 "Eco2.User" user "User.Eco2")
		(25 "Edge.Cuts" user "Board Geometry/Outline")
		(27 "Margin" user)
		(31 "F.CrtYd" user "Package Geometry/Place Bound Top")
		(29 "B.CrtYd" user "Package Geometry/Place Bound Bottom")
		(35 "F.Fab" user "Ref Des/Assembly Top")
		(33 "B.Fab" user "Ref Des/Assembly Bottom")
	)
	(footprint ""
		(layer "F.Cu")
		(at 363.8804 -136.7536 90)
		(property "Reference" "R12W29"
			(at -0.8382 -0.67818 90)
			(unlocked yes)
			(layer "F.SilkS")
			(effects
				(font
					(size 0.4064 0.254)
					(thickness 0.1524)
				)
				(justify left)
			)
		)
		(property "Value" ""
			(at 0 0 90)
			(layer "F.Fab")
			(effects
				(font
					(size 1.27 1.27)
				)
			)
		)
		(duplicate_pad_numbers_are_jumpers no)
		(fp_poly
			(pts
				(xy -0.2794 -0.1016) (xy 0.2794 -0.1016) (xy 0.2794 0.9906) (xy -0.2794 0.9906)
			)
			(stroke
				(width 0)
				(type default)
			)
			(fill no)
			(layer "F.CrtYd")
		)
		(fp_line
			(start 0.2794 -0.1016)
			(end -0.2794 -0.1016)
			(stroke
				(width 0.1)
				(type default)
			)
			(layer "F.Fab")
		)
		(fp_line
			(start -0.2794 -0.1016)
			(end -0.2794 0.9906)
			(stroke
				(width 0.1)
				(type default)
			)
			(layer "F.Fab")
		)
		(fp_line
			(start 0.2794 0.9906)
			(end 0.2794 -0.1016)
			(stroke
				(width 0.1)
				(type default)
			)
			(layer "F.Fab")
		)
		(fp_line
			(start -0.2794 0.9906)
			(end 0.2794 0.9906)
			(stroke
				(width 0.1)
				(type default)
			)
			(layer "F.Fab")
		)
		(pad "1" smd rect
			(at 0 0 90)
			(size 0.508 0.508)
			(layers "F.Cu" "F.Mask" "F.Paste")
			(net "TP_PVDDQ_DEF_MP1")
		)
		(pad "2" smd rect
			(at 0 0.889 90)
			(size 0.508 0.508)
			(layers "F.Cu" "F.Mask" "F.Paste")
			(net "PWRGD_PVDDQ_DEF")
		)
		(zone
			(layer "F.Cu")
			(hatch none 0.5)
			(connect_pads
				(clearance 0)
			)
			(min_thickness 0.25)
			(keepout
				(tracks allowed)
				(vias not_allowed)
				(pads allowed)
				(copperpour not_allowed)
				(footprints allowed)
			)
			(placement
				(enabled no)
				(sheetname "")
			)
			(fill
				(thermal_gap 0.5)
				(thermal_bridge_width 0.5)
				(island_removal_mode 0)
			)
			(polygon
				(pts
					(xy 364.1344 -136.4996) (xy 364.1344 -137.0076) (xy 364.5154 -137.0076) (xy 364.5154 -136.4996)
				)
			)
		)
		(zone
			(layer "F.Cu")
			(hatch none 0.5)
			(connect_pads
				(clearance 0)
			)
			(min_thickness 0.25)
			(keepout
				(tracks not_allowed)
				(vias allowed)
				(pads allowed)
				(copperpour not_allowed)
				(footprints allowed)
			)
			(placement
				(enabled no)
				(sheetname "")
			)
			(fill
				(thermal_gap 0.5)
				(thermal_bridge_width 0.5)
				(island_removal_mode 0)
			)
			(polygon
				(pts
					(xy 364.5154 -136.4996) (xy 364.5154 -137.0076) (xy 364.1344 -137.0076) (xy 364.1344 -136.4996)
				)
			)
		)
	)
	(footprint ""
		(layer "F.Cu")
		(at 266.920472 -77.636116)
		(property "Reference" "C5D31"
			(at 0 0 0)
			(layer "F.SilkS")
			(hide yes)
			(effects
				(font
					(size 1.27 1.27)
				)
			)
		)
		(property "Value" ""
			(at 0 0 0)
			(layer "F.Fab")
			(effects
				(font
					(size 1.27 1.27)
				)
			)
		)
		(duplicate_pad_numbers_are_jumpers no)
		(fp_poly
			(pts
				(xy -0.4953 -0.2032) (xy 0.4953 -0.2032) (xy 0.4953 1.6002) (xy -0.4953 1.6002)
			)
			(stroke
				(width 0)
				(type default)
			)
			(fill no)
			(layer "F.CrtYd")
		)
		(fp_line
			(start -0.4953 -0.2032)
			(end 0.4953 -0.2032)
			(stroke
				(width 0.1)
				(type default)
			)
			(layer "F.Fab")
		)
		(fp_line
			(start -0.4953 1.6002)
			(end -0.4953 -0.2032)
			(stroke
				(width 0.1)
				(type default)
			)
			(layer "F.Fab")
		)
		(fp_line
			(start 0.4953 -0.2032)
			(end 0.4953 1.6002)
			(stroke
				(width 0.1)
				(type default)
			)
			(layer "F.Fab")
		)
		(fp_line
			(start 0.4953 1.6002)
			(end -0.4953 1.6002)
			(stroke
				(width 0.1)
				(type default)
			)
			(layer "F.Fab")
		)
		(pad "1" smd rect
			(at 0 0)
			(size 0.762 0.889)
			(layers "F.Cu" "F.Mask" "F.Paste")
			(net "PVCCIN_CPU0")
		)
		(pad "2" smd rect
			(at 0 1.397)
			(size 0.762 0.889)
			(layers "F.Cu" "F.Mask" "F.Paste")
			(net "GND")
		)
		(zone
			(layer "F.Cu")
			(hatch none 0.5)
			(connect_pads
				(clearance 0)
			)
			(min_thickness 0.25)
			(keepout
				(tracks not_allowed)
				(vias allowed)
				(pads allowed)
				(copperpour not_allowed)
				(footprints allowed)
			)
			(placement
				(enabled no)
				(sheetname "")
			)
			(fill
				(thermal_gap 0.5)
				(thermal_bridge_width 0.5)
				(island_removal_mode 0)
			)
			(polygon
				(pts
					(xy 266.539472 -77.191616) (xy 267.301472 -77.191616) (xy 267.301472 -76.683616) (xy 266.539472 -76.683616)
				)
			)
		)
	)
	(footprint ""
		(layer "F.Cu")
		(at 403.987 -115.697 90)
		(property "Reference" "R25W140"
			(at -0.8382 -0.67818 90)
			(unlocked yes)
			(layer "F.SilkS")
			(effects
				(font
					(size 0.4064 0.254)
					(thickness 0.1524)
				)
				(justify left)
			)
		)
		(property "Value" ""
			(at 0 0 90)
			(layer "F.Fab")
			(effects
				(font
					(size 1.27 1.27)
				)
			)
		)
		(duplicate_pad_numbers_are_jumpers no)
		(fp_poly
			(pts
				(xy -0.2794 -0.1016) (xy 0.2794 -0.1016) (xy 0.2794 0.9906) (xy -0.2794 0.9906)
			)
			(stroke
				(width 0)
				(type default)
			)
			(fill no)
			(layer "F.CrtYd")
		)
		(fp_line
			(start 0.2794 -0.1016)
			(end -0.2794 -0.1016)
			(stroke
				(width 0.1)
				(type default)
			)
			(layer "F.Fab")
		)
		(fp_line
			(start -0.2794 -0.1016)
			(end -0.2794 0.9906)
			(stroke
				(width 0.1)
				(type default)
			)
			(layer "F.Fab")
		)
		(fp_line
			(start 0.2794 0.9906)
			(end 0.2794 -0.1016)
			(stroke
				(width 0.1)
				(type default)
			)
			(layer "F.Fab")
		)
		(fp_line
			(start -0.2794 0.9906)
			(end 0.2794 0.9906)
			(stroke
				(width 0.1)
				(type default)
			)
			(layer "F.Fab")
		)
		(pad "1" smd rect
			(at 0 0 90)
			(size 0.508 0.508)
			(layers "F.Cu" "F.Mask" "F.Paste")
			(net "CLK_48M_USB_BMC")
		)
		(pad "2" smd rect
			(at 0 0.889 90)
			(size 0.508 0.508)
			(layers "F.Cu" "F.Mask" "F.Paste")
			(net "CLK_48M_USB_BMC_R")
		)
		(zone
			(layer "F.Cu")
			(hatch none 0.5)
			(connect_pads
				(clearance 0)
			)
			(min_thickness 0.25)
			(keepout
				(tracks allowed)
				(vias not_allowed)
				(pads allowed)
				(copperpour not_allowed)
				(footprints allowed)
			)
			(placement
				(enabled no)
				(sheetname "")
			)
			(fill
				(thermal_gap 0.5)
				(thermal_bridge_width 0.5)
				(island_removal_mode 0)
			)
			(polygon
				(pts
					(xy 404.241 -115.443) (xy 404.241 -115.951) (xy 404.622 -115.951) (xy 404.622 -115.443)
				)
			)
		)
		(zone
			(layer "F.Cu")
			(hatch none 0.5)
			(connect_pads
				(clearance 0)
			)
			(min_thickness 0.25)
			(keepout
				(tracks not_allowed)
				(vias allowed)
				(pads allowed)
				(copperpour not_allowed)
				(footprints allowed)
			)
			(placement
				(enabled no)
				(sheetname "")
			)
			(fill
				(thermal_gap 0.5)
				(thermal_bridge_width 0.5)
				(island_removal_mode 0)
			)
			(polygon
				(pts
					(xy 404.622 -115.443) (xy 404.622 -115.951) (xy 404.241 -115.951) (xy 404.241 -115.443)
				)
			)
		)
	)
)
